(kicad_pcb
	(version 20260206)
	(generator "pcbnew")
	(generator_version "10.0")
	(general
		(thickness 1.6)
		(legacy_teardrops no)
	)
	(paper "A4")
	(title_block
		(title "dpb — 14545-sa.0730WZS0815.brd")
		(comment 1 "Honey Badger (Wiwynn) / footprints 320-322 of 1066")
	)
	(layers
		(0 "F.Cu" signal "TOP")
		(4 "In1.Cu" signal "L2GND")
		(6 "In2.Cu" signal "L3")
		(8 "In3.Cu" signal "L4VCC")
		(10 "In4.Cu" signal "L5VCC")
		(12 "In5.Cu" signal "L6")
		(14 "In6.Cu" signal "L7GND")
		(2 "B.Cu" signal "BOTTOM")
		(9 "F.Adhes" user "F.Adhesive")
		(11 "B.Adhes" user "B.Adhesive")
		(13 "F.Paste" user "Package Geometry/Pastemask Top")
		(15 "B.Paste" user "Package Geometry/Pastemask Bottom")
		(5 "F.SilkS" user "Ref Des/Silkscreen Top")
		(7 "B.SilkS" user "Ref Des/Silkscreen Bottom")
		(1 "F.Mask" user "Board Geometry/Soldermask Top")
		(3 "B.Mask" user "Board Geometry/Soldermask Bottom")
		(17 "Dwgs.User" user "User.Drawings")
		(19 "Cmts.User" user "User.Comments")
		(21 "Eco1.User" user "User.Eco1")
		(23 "Eco2.User" user "User.Eco2")
		(25 "Edge.Cuts" user "Board Geometry/Outline")
		(27 "Margin" user)
		(31 "F.CrtYd" user "Package Geometry/Place Bound Top")
		(29 "B.CrtYd" user "Package Geometry/Place Bound Bottom")
		(35 "F.Fab" user "Ref Des/Assembly Top")
		(33 "B.Fab" user "Ref Des/Assembly Bottom")
	)
	(footprint ""
		(layer "F.Cu")
		(at 27.888946 -281.7368 90)
		(property "Reference" "Q16"
			(at 0 0 90)
			(layer "F.SilkS")
			(hide yes)
			(effects
				(font
					(size 1.27 1.27)
				)
			)
		)
		(property "Value" "2N7002DW-7F-GP"
			(at -2.3622 -8.2042 90)
			(unlocked yes)
			(layer "F.Fab")
			(hide yes)
			(effects
				(font
					(size 1.016 1.016)
					(thickness 0.1524)
				)
			)
		)
		(property "Device Type" "SOT-363H44"
			(at -2.3622 -10.1092 90)
			(unlocked yes)
			(layer "F.Fab")
			(hide yes)
			(effects
				(font
					(size 1.016 1.016)
					(thickness 0.1524)
				)
			)
		)
		(duplicate_pad_numbers_are_jumpers no)
		(fp_line
			(start 1.4478 -1.7018)
			(end -1.4478 -1.7018)
			(stroke
				(width 0.1524)
				(type default)
			)
			(layer "F.SilkS")
		)
		(fp_line
			(start -1.4478 -1.7018)
			(end -1.4478 1.7018)
			(stroke
				(width 0.1524)
				(type default)
			)
			(layer "F.SilkS")
		)
		(fp_line
			(start -1.27 1.524)
			(end -1.27 0.6604)
			(stroke
				(width 0.4826)
				(type default)
			)
			(layer "F.SilkS")
		)
		(fp_line
			(start 1.4478 1.7018)
			(end 1.4478 -1.7018)
			(stroke
				(width 0.1524)
				(type default)
			)
			(layer "F.SilkS")
		)
		(fp_line
			(start -1.4478 1.7018)
			(end 1.4478 1.7018)
			(stroke
				(width 0.1524)
				(type default)
			)
			(layer "F.SilkS")
		)
		(fp_poly
			(pts
				(xy -1.524 -1.778) (xy 1.524 -1.778) (xy 1.524 1.778) (xy -1.524 1.778)
			)
			(stroke
				(width 0)
				(type default)
			)
			(fill no)
			(layer "F.CrtYd")
		)
		(fp_poly
			(pts
				(xy -1.524 -1.778) (xy 1.524 -1.778) (xy 1.524 1.778) (xy -1.524 1.778)
			)
			(stroke
				(width 0)
				(type default)
			)
			(fill no)
			(layer "F.Fab")
		)
		(pad "1" smd rect
			(at -0.65024 0.9398 90)
			(size 0.4064 1.016)
			(layers "F.Cu" "F.Mask" "F.Paste")
			(net "GND")
		)
		(pad "2" smd rect
			(at 0 0.9398 90)
			(size 0.4064 1.016)
			(layers "F.Cu" "F.Mask" "F.Paste")
			(net "SW_PWR_R_HDD7")
		)
		(pad "3" smd rect
			(at 0.65024 0.9398 90)
			(size 0.4064 1.016)
			(layers "F.Cu" "F.Mask" "F.Paste")
			(net "SW_HDD7_P")
		)
		(pad "4" smd rect
			(at 0.65024 -0.9398 90)
			(size 0.4064 1.016)
			(layers "F.Cu" "F.Mask" "F.Paste")
			(net "GND")
		)
		(pad "5" smd rect
			(at 0 -0.9398 90)
			(size 0.4064 1.016)
			(layers "F.Cu" "F.Mask" "F.Paste")
			(net "SW_HDD7_G")
		)
		(pad "6" smd rect
			(at -0.65024 -0.9398 90)
			(size 0.4064 1.016)
			(layers "F.Cu" "F.Mask" "F.Paste")
			(net "SW_HDD7_R")
		)
	)
	(footprint ""
		(layer "F.Cu")
		(at 80.391 -403.098 -90)
		(property "Reference" "R193"
			(at 0 0 270)
			(layer "F.SilkS")
			(hide yes)
			(effects
				(font
					(size 1.27 1.27)
				)
			)
		)
		(property "Value" "4K7R2J-2-GP"
			(at 0.064008 -3.993896 270)
			(unlocked yes)
			(layer "F.Fab")
			(hide yes)
			(effects
				(font
					(size 1.016 1.016)
					(thickness 0.1524)
				)
			)
		)
		(property "Device Type" "R402H16"
			(at 0.064008 -5.517896 270)
			(unlocked yes)
			(layer "F.Fab")
			(hide yes)
			(effects
				(font
					(size 1.016 1.016)
					(thickness 0.1524)
				)
			)
		)
		(duplicate_pad_numbers_are_jumpers no)
		(fp_line
			(start -0.508 -0.9398)
			(end -0.508 0.9398)
			(stroke
				(width 0.1524)
				(type default)
			)
			(layer "F.SilkS")
		)
		(fp_line
			(start 0.508 -0.9398)
			(end -0.508 -0.9398)
			(stroke
				(width 0.1524)
				(type default)
			)
			(layer "F.SilkS")
		)
		(fp_rect
			(start -0.508 0.9398)
			(end 0.508 -0.9398)
			(stroke
				(width 0)
				(type default)
			)
			(fill no)
			(layer "F.CrtYd")
		)
		(fp_rect
			(start -0.508 0.9398)
			(end 0.508 -0.9398)
			(stroke
				(width 0)
				(type default)
			)
			(fill no)
			(layer "F.Fab")
		)
		(pad "1" smd custom
			(at 0 -0.4445 270)
			(size 0.1397 0.1397)
			(layers "F.Cu" "F.Mask" "F.Paste")
			(net "P12V")
			(options
				(clearance outline)
				(anchor circle)
			)
			(primitives
				(gr_poly
					(pts
						(arc
							(start -0.1778 -0.2794)
							(mid -0.249642 -0.249642)
							(end -0.2794 -0.1778)
						)
						(arc
							(start -0.2794 0.1778)
							(mid -0.249642 0.249642)
							(end -0.1778 0.2794)
						)
						(arc
							(start 0.1778 0.2794)
							(mid 0.249642 0.249642)
							(end 0.2794 0.1778)
						)
						(arc
							(start 0.2794 -0.1778)
							(mid 0.249642 -0.249642)
							(end 0.1778 -0.2794)
						)
					)
					(width 0)
					(fill yes)
				)
			)
		)
		(pad "2" smd custom
			(at 0 0.4445 270)
			(size 0.1397 0.1397)
			(layers "F.Cu" "F.Mask" "F.Paste")
			(net "SW_HDD6_R")
			(options
				(clearance outline)
				(anchor circle)
			)
			(primitives
				(gr_poly
					(pts
						(arc
							(start -0.1778 -0.2794)
							(mid -0.249642 -0.249642)
							(end -0.2794 -0.1778)
						)
						(arc
							(start -0.2794 0.1778)
							(mid -0.249642 0.249642)
							(end -0.1778 0.2794)
						)
						(arc
							(start 0.1778 0.2794)
							(mid 0.249642 0.249642)
							(end 0.2794 0.1778)
						)
						(arc
							(start 0.2794 -0.1778)
							(mid 0.249642 -0.249642)
							(end 0.1778 -0.2794)
						)
					)
					(width 0)
					(fill yes)
				)
			)
		)
	)
	(footprint ""
		(layer "F.Cu")
		(at 19.05 -397.9926)
		(property "Reference" "R481"
			(at 0 0 0)
			(layer "F.SilkS")
			(hide yes)
			(effects
				(font
					(size 1.27 1.27)
				)
			)
		)
		(property "Value" "0R2J-2-GP"
			(at 0.064008 -3.993896 0)
			(unlocked yes)
			(layer "F.Fab")
			(hide yes)
			(effects
				(font
					(size 1.016 1.016)
					(thickness 0.1524)
				)
			)
		)
		(property "Device Type" "R402H16"
			(at 0.064008 -5.517896 0)
			(unlocked yes)
			(layer "F.Fab")
			(hide yes)
			(effects
				(font
					(size 1.016 1.016)
					(thickness 0.1524)
				)
			)
		)
		(duplicate_pad_numbers_are_jumpers no)
		(fp_line
			(start -0.508 -0.9398)
			(end -0.508 0.9398)
			(stroke
				(width 0.1524)
				(type default)
			)
			(layer "F.SilkS")
		)
		(fp_line
			(start 0.508 -0.9398)
			(end -0.508 -0.9398)
			(stroke
				(width 0.1524)
				(type default)
			)
			(layer "F.SilkS")
		)
		(fp_rect
			(start -0.508 0.9398)
			(end 0.508 -0.9398)
			(stroke
				(width 0)
				(type default)
			)
			(fill no)
			(layer "F.CrtYd")
		)
		(fp_rect
			(start -0.508 0.9398)
			(end 0.508 -0.9398)
			(stroke
				(width 0)
				(type default)
			)
			(fill no)
			(layer "F.Fab")
		)
		(pad "1" smd custom
			(at 0 -0.4445)
			(size 0.1397 0.1397)
			(layers "F.Cu" "F.Mask" "F.Paste")
			(net "I2C_C_SCL_DAMP_A")
			(options
				(clearance outline)
				(anchor circle)
			)
			(primitives
				(gr_poly
					(pts
						(arc
							(start -0.1778 -0.2794)
							(mid -0.249642 -0.249642)
							(end -0.2794 -0.1778)
						)
						(arc
							(start -0.2794 0.1778)
							(mid -0.249642 0.249642)
							(end -0.1778 0.2794)
						)
						(arc
							(start 0.1778 0.2794)
							(mid 0.249642 0.249642)
							(end 0.2794 0.1778)
						)
						(arc
							(start 0.2794 -0.1778)
							(mid 0.249642 -0.249642)
							(end 0.1778 -0.2794)
						)
					)
					(width 0)
					(fill yes)
				)
			)
		)
		(pad "2" smd custom
			(at 0 0.4445)
			(size 0.1397 0.1397)
			(layers "F.Cu" "F.Mask" "F.Paste")
			(net "I2C_C_SCL")
			(options
				(clearance outline)
				(anchor circle)
			)
			(primitives
				(gr_poly
					(pts
						(arc
							(start -0.1778 -0.2794)
							(mid -0.249642 -0.249642)
							(end -0.2794 -0.1778)
						)
						(arc
							(start -0.2794 0.1778)
							(mid -0.249642 0.249642)
							(end -0.1778 0.2794)
						)
						(arc
							(start 0.1778 0.2794)
							(mid 0.249642 0.249642)
							(end 0.2794 0.1778)
						)
						(arc
							(start 0.2794 -0.1778)
							(mid 0.249642 -0.249642)
							(end 0.1778 -0.2794)
						)
					)
					(width 0)
					(fill yes)
				)
			)
		)
	)
)
